G04*
G04 #@! TF.GenerationSoftware,Altium Limited,Altium Designer,23.0.1 (38)*
G04*
G04 Layer_Physical_Order=2*
G04 Layer_Color=36540*
%FSLAX44Y44*%
%MOMM*%
G71*
G04*
G04 #@! TF.SameCoordinates,9A23C038-B079-480F-8166-AFFB5740F5AE*
G04*
G04*
G04 #@! TF.FilePolarity,Positive*
G04*
G01*
G75*
%ADD46C,0.5500*%
%ADD47C,0.5588*%
G36*
X662899Y313154D02*
X664122Y312648D01*
X665223Y311913D01*
X666159Y310977D01*
X666895Y309878D01*
X667402Y308655D01*
X667661Y307358D01*
X667662Y306697D01*
X667632Y10150D01*
X667632Y10150D01*
X667632Y10150D01*
X667632Y9548D01*
X667397Y8368D01*
X666937Y7257D01*
X666269Y6256D01*
X665419Y5405D01*
X664419Y4736D01*
X663307Y4275D01*
X662128Y4039D01*
X661526Y4038D01*
X10450Y4078D01*
X10450Y4078D01*
X10450Y4078D01*
X9822D01*
X8591Y4323D01*
X7432Y4803D01*
X6388Y5501D01*
X5501Y6388D01*
X4803Y7432D01*
X4323Y8591D01*
X4078Y9822D01*
X4078Y10450D01*
X4078Y10450D01*
X4078Y10450D01*
X4058Y306760D01*
D01*
X4058Y307413D01*
X4313Y308693D01*
X4812Y309900D01*
X5537Y310985D01*
X6460Y311909D01*
X7545Y312635D01*
X8751Y313135D01*
X10031Y313391D01*
X10684Y313392D01*
D01*
X660940Y313412D01*
X661602D01*
X662899Y313154D01*
D02*
G37*
%LPC*%
G36*
X635037Y308538D02*
X631983D01*
X631589Y308460D01*
X631188D01*
X628193Y307864D01*
X627822Y307711D01*
X627428Y307632D01*
X624607Y306464D01*
X624273Y306241D01*
X623902Y306087D01*
X621363Y304391D01*
X621079Y304107D01*
X620746Y303883D01*
X618587Y301724D01*
X618363Y301390D01*
X618079Y301106D01*
X616383Y298568D01*
X616229Y298197D01*
X616006Y297863D01*
X614838Y295042D01*
X614759Y294648D01*
X614606Y294277D01*
X614010Y291282D01*
Y290881D01*
X613932Y290487D01*
Y288960D01*
Y287433D01*
X614010Y287039D01*
Y286638D01*
X614606Y283643D01*
X614759Y283272D01*
X614838Y282878D01*
X616006Y280057D01*
X616229Y279723D01*
X616383Y279352D01*
X618079Y276814D01*
X618363Y276529D01*
X618587Y276196D01*
X620746Y274037D01*
X621079Y273813D01*
X621363Y273529D01*
X623902Y271833D01*
X624273Y271679D01*
X624607Y271456D01*
X627428Y270288D01*
X627822Y270209D01*
X628193Y270056D01*
X631188Y269460D01*
X631589D01*
X631983Y269382D01*
X635037D01*
X635431Y269460D01*
X635832D01*
X638827Y270056D01*
X639198Y270209D01*
X639592Y270288D01*
X642413Y271456D01*
X642747Y271679D01*
X643118Y271833D01*
X645657Y273529D01*
X645941Y273813D01*
X646274Y274037D01*
X648434Y276196D01*
X648657Y276530D01*
X648941Y276814D01*
X650637Y279352D01*
X650791Y279723D01*
X651014Y280057D01*
X652182Y282878D01*
X652261Y283272D01*
X652414Y283643D01*
X653010Y286638D01*
Y287039D01*
X653088Y287433D01*
Y288960D01*
Y290487D01*
X653010Y290881D01*
Y291282D01*
X652414Y294277D01*
X652261Y294648D01*
X652182Y295042D01*
X651014Y297863D01*
X650791Y298197D01*
X650637Y298568D01*
X648941Y301106D01*
X648657Y301391D01*
X648434Y301724D01*
X646274Y303883D01*
X645940Y304107D01*
X645657Y304391D01*
X643118Y306087D01*
X642747Y306241D01*
X642413Y306464D01*
X639592Y307632D01*
X639198Y307711D01*
X638827Y307864D01*
X635832Y308460D01*
X635431D01*
X635037Y308538D01*
D02*
G37*
G36*
X30037D02*
X26983D01*
X26589Y308460D01*
X26188D01*
X23193Y307864D01*
X22822Y307711D01*
X22428Y307632D01*
X19607Y306464D01*
X19273Y306241D01*
X18902Y306087D01*
X16364Y304391D01*
X16079Y304107D01*
X15746Y303883D01*
X13586Y301724D01*
X13363Y301390D01*
X13079Y301106D01*
X11383Y298568D01*
X11229Y298197D01*
X11006Y297863D01*
X9838Y295042D01*
X9759Y294648D01*
X9606Y294277D01*
X9010Y291282D01*
Y290881D01*
X8932Y290487D01*
Y288960D01*
Y287433D01*
X9010Y287039D01*
Y286638D01*
X9606Y283643D01*
X9759Y283272D01*
X9838Y282878D01*
X11006Y280057D01*
X11229Y279723D01*
X11383Y279352D01*
X13079Y276814D01*
X13363Y276529D01*
X13586Y276196D01*
X15746Y274037D01*
X16079Y273813D01*
X16364Y273529D01*
X18902Y271833D01*
X19273Y271679D01*
X19607Y271456D01*
X22428Y270288D01*
X22822Y270209D01*
X23193Y270056D01*
X26188Y269460D01*
X26589D01*
X26983Y269382D01*
X30037D01*
X30431Y269460D01*
X30832D01*
X33827Y270056D01*
X34198Y270209D01*
X34592Y270288D01*
X37413Y271456D01*
X37747Y271679D01*
X38118Y271833D01*
X40656Y273529D01*
X40941Y273813D01*
X41274Y274037D01*
X43433Y276196D01*
X43657Y276530D01*
X43941Y276814D01*
X45637Y279352D01*
X45791Y279723D01*
X46014Y280057D01*
X47182Y282878D01*
X47261Y283272D01*
X47414Y283643D01*
X48010Y286638D01*
Y287039D01*
X48088Y287433D01*
Y288960D01*
Y290487D01*
X48010Y290881D01*
Y291282D01*
X47414Y294277D01*
X47261Y294648D01*
X47182Y295042D01*
X46014Y297863D01*
X45791Y298197D01*
X45637Y298568D01*
X43941Y301106D01*
X43657Y301391D01*
X43433Y301724D01*
X41274Y303883D01*
X40940Y304107D01*
X40656Y304391D01*
X38118Y306087D01*
X37747Y306241D01*
X37413Y306464D01*
X34592Y307632D01*
X34198Y307711D01*
X33827Y307864D01*
X30832Y308460D01*
X30431D01*
X30037Y308538D01*
D02*
G37*
G36*
X523910Y246750D02*
X522020D01*
X520274Y246027D01*
X518938Y244691D01*
X518215Y242945D01*
Y241055D01*
X518938Y239309D01*
X520274Y237973D01*
X522020Y237250D01*
X523910D01*
X525656Y237973D01*
X526992Y239309D01*
X527715Y241055D01*
Y242945D01*
X526992Y244691D01*
X525656Y246027D01*
X523910Y246750D01*
D02*
G37*
G36*
X536945Y237441D02*
X535055D01*
X533309Y236717D01*
X531973Y235381D01*
X531250Y233636D01*
Y231746D01*
X531973Y230000D01*
X533309Y228664D01*
X535055Y227941D01*
X536945D01*
X538691Y228664D01*
X540027Y230000D01*
X540750Y231746D01*
Y233636D01*
X540027Y235381D01*
X538691Y236717D01*
X536945Y237441D01*
D02*
G37*
G36*
X523945Y212789D02*
X522055D01*
X520309Y212066D01*
X518973Y210730D01*
X518250Y208984D01*
Y207094D01*
X518973Y205349D01*
X520309Y204013D01*
X522055Y203289D01*
X523945D01*
X525691Y204013D01*
X527027Y205349D01*
X527750Y207094D01*
Y208984D01*
X527027Y210730D01*
X525691Y212066D01*
X523945Y212789D01*
D02*
G37*
G36*
X536945Y212750D02*
X535055D01*
X533309Y212027D01*
X531973Y210691D01*
X531250Y208945D01*
Y207055D01*
X531973Y205309D01*
X533309Y203973D01*
X535055Y203250D01*
X536945D01*
X538691Y203973D01*
X540027Y205309D01*
X540750Y207055D01*
Y208945D01*
X540027Y210691D01*
X538691Y212027D01*
X536945Y212750D01*
D02*
G37*
G36*
X561945Y127750D02*
X560055D01*
X558309Y127027D01*
X556973Y125691D01*
X556250Y123945D01*
Y122055D01*
X556973Y120309D01*
X558309Y118973D01*
X560055Y118250D01*
X561945D01*
X563691Y118973D01*
X565027Y120309D01*
X565750Y122055D01*
Y123945D01*
X565027Y125691D01*
X563691Y127027D01*
X561945Y127750D01*
D02*
G37*
G36*
Y107750D02*
X560055D01*
X558309Y107027D01*
X556973Y105691D01*
X556250Y103945D01*
Y102055D01*
X556973Y100309D01*
X558309Y98973D01*
X560055Y98250D01*
X561945D01*
X563691Y98973D01*
X565027Y100309D01*
X565750Y102055D01*
Y103945D01*
X565027Y105691D01*
X563691Y107027D01*
X561945Y107750D01*
D02*
G37*
G36*
X635037Y48538D02*
X631983D01*
X631589Y48460D01*
X631188D01*
X628193Y47864D01*
X627822Y47711D01*
X627428Y47632D01*
X624607Y46464D01*
X624273Y46241D01*
X623902Y46087D01*
X621363Y44391D01*
X621079Y44107D01*
X620746Y43884D01*
X618587Y41725D01*
X618363Y41391D01*
X618079Y41107D01*
X616383Y38568D01*
X616229Y38197D01*
X616006Y37863D01*
X614838Y35042D01*
X614759Y34648D01*
X614606Y34277D01*
X614010Y31282D01*
Y30881D01*
X613932Y30487D01*
Y28960D01*
Y27433D01*
X614010Y27039D01*
Y26638D01*
X614606Y23643D01*
X614759Y23272D01*
X614838Y22878D01*
X616006Y20057D01*
X616229Y19723D01*
X616383Y19352D01*
X618079Y16813D01*
X618363Y16529D01*
X618587Y16195D01*
X620746Y14037D01*
X621079Y13813D01*
X621363Y13529D01*
X623902Y11833D01*
X624273Y11679D01*
X624607Y11456D01*
X627428Y10288D01*
X627822Y10209D01*
X628193Y10056D01*
X631188Y9460D01*
X631589D01*
X631983Y9382D01*
X635037D01*
X635431Y9460D01*
X635832D01*
X638827Y10056D01*
X639198Y10209D01*
X639592Y10288D01*
X642413Y11456D01*
X642747Y11679D01*
X643118Y11833D01*
X645657Y13529D01*
X645941Y13813D01*
X646274Y14037D01*
X648434Y16195D01*
X648657Y16530D01*
X648941Y16813D01*
X650637Y19352D01*
X650791Y19723D01*
X651014Y20057D01*
X652182Y22878D01*
X652261Y23272D01*
X652414Y23643D01*
X653010Y26638D01*
Y27039D01*
X653088Y27433D01*
Y28960D01*
Y30487D01*
X653010Y30881D01*
Y31282D01*
X652414Y34277D01*
X652261Y34648D01*
X652182Y35042D01*
X651014Y37863D01*
X650791Y38197D01*
X650637Y38568D01*
X648941Y41107D01*
X648657Y41391D01*
X648434Y41725D01*
X646274Y43884D01*
X645940Y44107D01*
X645657Y44391D01*
X643118Y46087D01*
X642747Y46241D01*
X642413Y46464D01*
X639592Y47632D01*
X639198Y47711D01*
X638827Y47864D01*
X635832Y48460D01*
X635431D01*
X635037Y48538D01*
D02*
G37*
G36*
X30037D02*
X26983D01*
X26589Y48460D01*
X26188D01*
X23193Y47864D01*
X22822Y47711D01*
X22428Y47632D01*
X19607Y46464D01*
X19273Y46241D01*
X18902Y46087D01*
X16364Y44391D01*
X16079Y44107D01*
X15746Y43884D01*
X13586Y41725D01*
X13363Y41391D01*
X13079Y41107D01*
X11383Y38568D01*
X11229Y38197D01*
X11006Y37863D01*
X9838Y35042D01*
X9759Y34648D01*
X9606Y34277D01*
X9010Y31282D01*
Y30881D01*
X8932Y30487D01*
Y28960D01*
Y27433D01*
X9010Y27039D01*
Y26638D01*
X9606Y23643D01*
X9759Y23272D01*
X9838Y22878D01*
X11006Y20057D01*
X11229Y19723D01*
X11383Y19352D01*
X13079Y16813D01*
X13363Y16529D01*
X13586Y16195D01*
X15746Y14037D01*
X16079Y13813D01*
X16364Y13529D01*
X18902Y11833D01*
X19273Y11679D01*
X19607Y11456D01*
X22428Y10288D01*
X22822Y10209D01*
X23193Y10056D01*
X26188Y9460D01*
X26589D01*
X26983Y9382D01*
X30037D01*
X30431Y9460D01*
X30832D01*
X33827Y10056D01*
X34198Y10209D01*
X34592Y10288D01*
X37413Y11456D01*
X37747Y11679D01*
X38118Y11833D01*
X40656Y13529D01*
X40941Y13813D01*
X41274Y14037D01*
X43433Y16195D01*
X43657Y16530D01*
X43941Y16813D01*
X45637Y19352D01*
X45791Y19723D01*
X46014Y20057D01*
X47182Y22878D01*
X47261Y23272D01*
X47414Y23643D01*
X48010Y26638D01*
Y27039D01*
X48088Y27433D01*
Y28960D01*
Y30487D01*
X48010Y30881D01*
Y31282D01*
X47414Y34277D01*
X47261Y34648D01*
X47182Y35042D01*
X46014Y37863D01*
X45791Y38197D01*
X45637Y38568D01*
X43941Y41107D01*
X43657Y41391D01*
X43433Y41725D01*
X41274Y43884D01*
X40940Y44107D01*
X40656Y44391D01*
X38118Y46087D01*
X37747Y46241D01*
X37413Y46464D01*
X34592Y47632D01*
X34198Y47711D01*
X33827Y47864D01*
X30832Y48460D01*
X30431D01*
X30037Y48538D01*
D02*
G37*
%LPD*%
D46*
X241871Y254805D02*
D03*
X231291D02*
D03*
X220711D02*
D03*
X210131D02*
D03*
X199634Y253481D02*
D03*
X190160Y248771D02*
D03*
X182390Y241591D02*
D03*
X174908Y234110D02*
D03*
X167427Y226629D02*
D03*
X159946Y219147D02*
D03*
X152465Y211666D02*
D03*
X144033Y205276D02*
D03*
X133555Y203805D02*
D03*
X122976D02*
D03*
X112410Y204354D02*
D03*
X101844Y203805D02*
D03*
X91264D02*
D03*
X80684D02*
D03*
X70105Y203927D02*
D03*
X62147Y210899D02*
D03*
X51602Y210033D02*
D03*
X44897Y201849D02*
D03*
X46109Y191339D02*
D03*
X54498Y184892D02*
D03*
X64966Y186424D02*
D03*
X73834Y192195D02*
D03*
X84414D02*
D03*
X94994D02*
D03*
X116052D02*
D03*
X126632D02*
D03*
X137212Y192229D02*
D03*
X147587Y194300D02*
D03*
X156682Y199706D02*
D03*
X164283Y207065D02*
D03*
X171765Y214546D02*
D03*
X179246Y222027D02*
D03*
X186727Y229508D02*
D03*
X194208Y236989D02*
D03*
X203283Y242429D02*
D03*
X213835Y243195D02*
D03*
X224415D02*
D03*
X234995D02*
D03*
X255209Y245785D02*
D03*
X252362Y255974D02*
D03*
X560000Y143000D02*
D03*
D47*
X175640Y128600D02*
D03*
X124840Y154000D02*
D03*
X150240Y103200D02*
D03*
X404029Y103411D02*
D03*
X455040Y128600D02*
D03*
X429640D02*
D03*
X404240D02*
D03*
X302640Y230200D02*
D03*
X632840Y255600D02*
D03*
Y230200D02*
D03*
Y204800D02*
D03*
Y154000D02*
D03*
Y52400D02*
D03*
X607440Y281000D02*
D03*
Y255600D02*
D03*
Y230200D02*
D03*
Y179400D02*
D03*
Y52400D02*
D03*
Y27000D02*
D03*
X582040Y281000D02*
D03*
Y255600D02*
D03*
Y154000D02*
D03*
Y52400D02*
D03*
X556640Y281000D02*
D03*
Y255600D02*
D03*
Y204800D02*
D03*
Y179400D02*
D03*
Y154000D02*
D03*
Y52400D02*
D03*
X531240Y281000D02*
D03*
Y255600D02*
D03*
Y52400D02*
D03*
X505840Y281000D02*
D03*
Y204800D02*
D03*
Y179400D02*
D03*
Y154000D02*
D03*
Y128600D02*
D03*
Y52400D02*
D03*
X480440Y281000D02*
D03*
Y255600D02*
D03*
Y204800D02*
D03*
Y179400D02*
D03*
Y154000D02*
D03*
Y128600D02*
D03*
Y103200D02*
D03*
Y52400D02*
D03*
X455040Y281000D02*
D03*
Y255600D02*
D03*
Y179400D02*
D03*
Y154000D02*
D03*
Y52400D02*
D03*
X429640Y281000D02*
D03*
Y255600D02*
D03*
Y230200D02*
D03*
Y154000D02*
D03*
Y103200D02*
D03*
Y77800D02*
D03*
Y52400D02*
D03*
X404240Y281000D02*
D03*
Y255600D02*
D03*
Y230200D02*
D03*
Y204800D02*
D03*
Y77800D02*
D03*
Y52400D02*
D03*
X378840Y281000D02*
D03*
Y179400D02*
D03*
Y52400D02*
D03*
X353440Y281000D02*
D03*
Y255600D02*
D03*
Y179400D02*
D03*
Y154000D02*
D03*
Y52400D02*
D03*
X328040Y281000D02*
D03*
Y179400D02*
D03*
Y154000D02*
D03*
Y128600D02*
D03*
Y52400D02*
D03*
X302640Y281000D02*
D03*
Y179400D02*
D03*
Y154000D02*
D03*
Y128600D02*
D03*
Y52400D02*
D03*
X277240Y281000D02*
D03*
Y179400D02*
D03*
Y154000D02*
D03*
Y128600D02*
D03*
Y77800D02*
D03*
Y52400D02*
D03*
X251840Y281000D02*
D03*
Y179400D02*
D03*
Y154000D02*
D03*
Y128600D02*
D03*
Y52400D02*
D03*
X226440Y281000D02*
D03*
Y230200D02*
D03*
Y204800D02*
D03*
Y179400D02*
D03*
Y154000D02*
D03*
Y128600D02*
D03*
Y103200D02*
D03*
Y27000D02*
D03*
X201040Y281000D02*
D03*
Y230200D02*
D03*
Y204800D02*
D03*
Y179400D02*
D03*
Y154000D02*
D03*
Y128600D02*
D03*
Y103200D02*
D03*
Y52400D02*
D03*
Y27000D02*
D03*
X175640Y281000D02*
D03*
Y255600D02*
D03*
Y204800D02*
D03*
Y179400D02*
D03*
Y154000D02*
D03*
Y77800D02*
D03*
Y52400D02*
D03*
Y27000D02*
D03*
X150240Y281000D02*
D03*
Y255600D02*
D03*
Y230200D02*
D03*
Y179400D02*
D03*
Y154000D02*
D03*
Y77800D02*
D03*
Y52400D02*
D03*
Y27000D02*
D03*
X124840Y281000D02*
D03*
Y255600D02*
D03*
Y230200D02*
D03*
Y77800D02*
D03*
Y52400D02*
D03*
Y27000D02*
D03*
X99440Y281000D02*
D03*
Y255600D02*
D03*
Y154000D02*
D03*
Y77800D02*
D03*
Y52400D02*
D03*
Y27000D02*
D03*
X74040Y281000D02*
D03*
Y255600D02*
D03*
Y230200D02*
D03*
Y179400D02*
D03*
Y154000D02*
D03*
Y128600D02*
D03*
Y103200D02*
D03*
Y77800D02*
D03*
Y52400D02*
D03*
Y27000D02*
D03*
X48640Y255600D02*
D03*
Y154000D02*
D03*
Y128600D02*
D03*
Y103200D02*
D03*
Y77800D02*
D03*
Y52400D02*
D03*
X23240Y255600D02*
D03*
Y154000D02*
D03*
Y128600D02*
D03*
Y103200D02*
D03*
Y77800D02*
D03*
Y52400D02*
D03*
M02*
